(kicad_pcb
	(version 20241229)
	(generator "pcbnew")
	(generator_version "9.0")
	(general
		(thickness 1.711)
		(legacy_teardrops no)
	)
	(paper "A4")
	(title_block
		(title "Antmicro Baseboard for Jetson AGX Thor")
		(date "2026-02-18")
		(rev "1.1.0")
		(company "Antmicro Ltd")
		(comment 1 "www.antmicro.com")
		(comment 9 "footprints 675-679 of 1170")
	)
	(layers
		(0 "F.Cu" signal)
		(4 "In1.Cu" signal)
		(6 "In2.Cu" signal)
		(8 "In3.Cu" signal)
		(10 "In4.Cu" jumper)
		(12 "In5.Cu" signal)
		(14 "In6.Cu" signal)
		(16 "In7.Cu" signal)
		(18 "In8.Cu" signal)
		(2 "B.Cu" signal)
		(9 "F.Adhes" user "F.Adhesive")
		(11 "B.Adhes" user "B.Adhesive")
		(13 "F.Paste" user)
		(15 "B.Paste" user)
		(5 "F.SilkS" user "F.Silkscreen")
		(7 "B.SilkS" user "B.Silkscreen")
		(1 "F.Mask" user)
		(3 "B.Mask" user)
		(17 "Dwgs.User" user "User.Drawings")
		(19 "Cmts.User" user "User.Comments")
		(21 "Eco1.User" user "User.Eco1")
		(23 "Eco2.User" user "User.Eco2")
		(25 "Edge.Cuts" user)
		(27 "Margin" user)
		(31 "F.CrtYd" user "F.Courtyard")
		(29 "B.CrtYd" user "B.Courtyard")
		(35 "F.Fab" user)
		(33 "B.Fab" user)
	)
	(footprint "antmicro-footprints:C_0603_1608Metric_EIA"
		(layer "B.Cu")
		(at 124.6 98.5)
		(descr "Capacitor SMD 0603, IPC-7351 Density Level A")
		(tags "Capacitor 0603")
		(property "Reference" "C190"
			(at 1.2 -0.5 0)
			(layer "B.SilkS")
			(effects
				(font
					(size 0.7 0.7)
					(thickness 0.15)
				)
				(justify right top mirror)
			)
		)
		(property "Value" "C_22u_16V_0603"
			(at -1.42757 -1.770288 0)
			(layer "B.Fab")
			(effects
				(font
					(size 0.7 0.7)
					(thickness 0.15)
				)
				(justify right top mirror)
			)
		)
		(property "Datasheet" "https://product.samsungsem.com/mlcc/CL10A226MO7JZN.do"
			(at 0 0 0)
			(layer "B.Fab")
			(hide yes)
			(effects
				(font
					(size 1.27 1.27)
					(thickness 0.15)
				)
				(justify mirror)
			)
		)
		(property "Description" "SMD Multilayer Ceramic Capacitor"
			(at 0 0 0)
			(layer "B.Fab")
			(hide yes)
			(effects
				(font
					(size 1.27 1.27)
					(thickness 0.15)
				)
				(justify mirror)
			)
		)
		(property "Manufacturer" "Samsung Electro-Mechanics"
			(at 0 0 180)
			(unlocked yes)
			(layer "B.Fab")
			(hide yes)
			(effects
				(font
					(size 1 1)
					(thickness 0.15)
				)
				(justify mirror)
			)
		)
		(property "MPN" "CL10A226MO7JZNC"
			(at 0 0 180)
			(unlocked yes)
			(layer "B.Fab")
			(hide yes)
			(effects
				(font
					(size 1 1)
					(thickness 0.15)
				)
				(justify mirror)
			)
		)
		(property "Val" "22u"
			(at 0 0 180)
			(unlocked yes)
			(layer "B.Fab")
			(hide yes)
			(effects
				(font
					(size 1 1)
					(thickness 0.15)
				)
				(justify mirror)
			)
		)
		(property "License" "Apache-2.0"
			(at 0 0 180)
			(unlocked yes)
			(layer "B.Fab")
			(hide yes)
			(effects
				(font
					(size 1 1)
					(thickness 0.15)
				)
				(justify mirror)
			)
		)
		(property "Author" "Antmicro"
			(at 0 0 180)
			(unlocked yes)
			(layer "B.Fab")
			(hide yes)
			(effects
				(font
					(size 1 1)
					(thickness 0.15)
				)
				(justify mirror)
			)
		)
		(property "Voltage" "16V"
			(at 0 0 180)
			(unlocked yes)
			(layer "B.Fab")
			(hide yes)
			(effects
				(font
					(size 1 1)
					(thickness 0.15)
				)
				(justify mirror)
			)
		)
		(property "Dielectric" "template_dielectric"
			(at 0 0 180)
			(unlocked yes)
			(layer "B.Fab")
			(hide yes)
			(effects
				(font
					(size 1 1)
					(thickness 0.15)
				)
				(justify mirror)
			)
		)
		(sheetname "/M.2/")
		(sheetfile "m2.kicad_sch")
		(attr smd)
		(fp_line
			(start -0.15 -0.55)
			(end 0.15 -0.55)
			(stroke
				(width 0.15)
				(type solid)
			)
			(layer "B.SilkS")
		)
		(fp_line
			(start -0.15 0.55)
			(end 0.15 0.55)
			(stroke
				(width 0.15)
				(type solid)
			)
			(layer "B.SilkS")
		)
		(fp_poly
			(pts
				(xy -1.25 0.65) (xy -1.25 -0.65) (xy 1.25 -0.65) (xy 1.25 0.65)
			)
			(stroke
				(width 0.05)
				(type solid)
			)
			(fill no)
			(layer "B.CrtYd")
		)
		(fp_poly
			(pts
				(xy -0.799999 0.45) (xy -0.799999 -0.45) (xy 0.799999 -0.45) (xy 0.799999 0.45)
			)
			(stroke
				(width 0.15)
				(type solid)
			)
			(fill no)
			(layer "B.Fab")
		)
		(fp_text user "Author: Antmicro"
			(at -1.682 -4.894 0)
			(layer "B.Fab")
			(effects
				(font
					(size 0.7 0.7)
					(thickness 0.15)
				)
				(justify right top mirror)
			)
		)
		(fp_text user "License: Apache-2.0"
			(at -1.682 -5.895 0)
			(layer "B.Fab")
			(effects
				(font
					(size 0.7 0.7)
					(thickness 0.15)
				)
				(justify right top mirror)
			)
		)
		(fp_text user "${REFERENCE}"
			(at -1.682001 -3.895 0)
			(layer "B.Fab")
			(effects
				(font
					(size 0.7 0.7)
					(thickness 0.15)
				)
				(justify right top mirror)
			)
		)
		(pad "1" smd roundrect
			(at -0.7 0)
			(size 0.8 1.1)
			(layers "B.Cu" "B.Mask" "B.Paste")
			(roundrect_rratio 0.2)
			(net 14 "/M.2/3V3_M2")
			(pintype "passive")
		)
		(pad "2" smd roundrect
			(at 0.7 0)
			(size 0.8 1.1)
			(layers "B.Cu" "B.Mask" "B.Paste")
			(roundrect_rratio 0.2)
			(net 1 "GND")
			(pintype "passive")
		)
	)
	(footprint "antmicro-footprints:C_0402_1005Metric"
		(layer "B.Cu")
		(at 95.68 105.51 90)
		(descr "Capacitor SMD 0402")
		(tags "capacitor SMD 0402")
		(property "Reference" "C333"
			(at -3.69 -0.28 90)
			(layer "B.SilkS")
			(effects
				(font
					(size 0.7 0.7)
					(thickness 0.15)
				)
				(justify right top mirror)
			)
		)
		(property "Value" "C_100n_0402"
			(at -1.022927 -2.155213 90)
			(layer "B.Fab")
			(effects
				(font
					(size 0.7 0.7)
					(thickness 0.15)
				)
				(justify right top mirror)
			)
		)
		(property "Datasheet" "https://www.murata.com/products/productdetail?partno=GRM155R61H104KE14%23"
			(at 0 0 90)
			(layer "B.Fab")
			(hide yes)
			(effects
				(font
					(size 1.27 1.27)
					(thickness 0.15)
				)
				(justify mirror)
			)
		)
		(property "Description" "SMD Multilayer Ceramic Capacitor, 0.1 µF, 50 V, 0402 [1005 Metric], ± 10%, X5R, GRM Series"
			(at 0 0 90)
			(layer "B.Fab")
			(hide yes)
			(effects
				(font
					(size 1.27 1.27)
					(thickness 0.15)
				)
				(justify mirror)
			)
		)
		(property "Manufacturer" "Murata"
			(at 0 0 270)
			(unlocked yes)
			(layer "B.Fab")
			(hide yes)
			(effects
				(font
					(size 1 1)
					(thickness 0.15)
				)
				(justify mirror)
			)
		)
		(property "MPN" "GRM155R61H104KE14D"
			(at 0 0 270)
			(unlocked yes)
			(layer "B.Fab")
			(hide yes)
			(effects
				(font
					(size 1 1)
					(thickness 0.15)
				)
				(justify mirror)
			)
		)
		(property "Val" "100n"
			(at 0 0 270)
			(unlocked yes)
			(layer "B.Fab")
			(hide yes)
			(effects
				(font
					(size 1 1)
					(thickness 0.15)
				)
				(justify mirror)
			)
		)
		(property "License" "Apache-2.0"
			(at 0 0 270)
			(unlocked yes)
			(layer "B.Fab")
			(hide yes)
			(effects
				(font
					(size 1 1)
					(thickness 0.15)
				)
				(justify mirror)
			)
		)
		(property "Author" "Antmicro"
			(at 0 0 270)
			(unlocked yes)
			(layer "B.Fab")
			(hide yes)
			(effects
				(font
					(size 1 1)
					(thickness 0.15)
				)
				(justify mirror)
			)
		)
		(property "Voltage" "50V"
			(at 0 0 270)
			(unlocked yes)
			(layer "B.Fab")
			(hide yes)
			(effects
				(font
					(size 1 1)
					(thickness 0.15)
				)
				(justify mirror)
			)
		)
		(property "Dielectric" "X5R"
			(at 0 0 270)
			(unlocked yes)
			(layer "B.Fab")
			(hide yes)
			(effects
				(font
					(size 1 1)
					(thickness 0.15)
				)
				(justify mirror)
			)
		)
		(sheetname "/SoM_IO2/")
		(sheetfile "som_io2.kicad_sch")
		(attr smd)
		(fp_poly
			(pts
				(xy -0.925 0.47) (xy 0.925 0.47) (xy 0.925 -0.47) (xy -0.925 -0.47)
			)
			(stroke
				(width 0.05)
				(type default)
			)
			(fill no)
			(layer "B.CrtYd")
		)
		(fp_line
			(start 0.504 -0.248)
			(end -0.494 -0.248)
			(stroke
				(width 0.15)
				(type solid)
			)
			(layer "B.Fab")
		)
		(fp_line
			(start -0.494 -0.248)
			(end -0.494 0.25)
			(stroke
				(width 0.15)
				(type solid)
			)
			(layer "B.Fab")
		)
		(fp_line
			(start 0.504 0.25)
			(end 0.504 -0.248)
			(stroke
				(width 0.15)
				(type solid)
			)
			(layer "B.Fab")
		)
		(fp_line
			(start -0.494 0.25)
			(end 0.504 0.25)
			(stroke
				(width 0.15)
				(type solid)
			)
			(layer "B.Fab")
		)
		(fp_text user "Author: Antmicro"
			(at -0.939 -3.399 90)
			(layer "B.Fab")
			(effects
				(font
					(size 0.7 0.7)
					(thickness 0.15)
				)
				(justify right top mirror)
			)
		)
		(fp_text user "${REFERENCE}"
			(at -0.939 -4.599 90)
			(layer "B.Fab")
			(effects
				(font
					(size 0.7 0.7)
					(thickness 0.15)
				)
				(justify right top mirror)
			)
		)
		(fp_text user "License: Apache-2.0"
			(at -0.939 -5.799 90)
			(layer "B.Fab")
			(effects
				(font
					(size 0.7 0.7)
					(thickness 0.15)
				)
				(justify right top mirror)
			)
		)
		(pad "1" smd roundrect
			(at -0.48 0 90)
			(size 0.59 0.64)
			(layers "B.Cu" "B.Mask" "B.Paste")
			(roundrect_rratio 0.25)
			(net 1253 "/SoM_IO2/DP1.AUX_C-")
			(pintype "passive")
		)
		(pad "2" smd roundrect
			(at 0.48 0 90)
			(size 0.59 0.64)
			(layers "B.Cu" "B.Mask" "B.Paste")
			(roundrect_rratio 0.25)
			(net 738 "/Expansion connector/DP1.AUX-")
			(pintype "passive")
		)
	)
	(footprint "antmicro-footprints:R_0402_1005Metric"
		(layer "B.Cu")
		(at 214.5 84.3 90)
		(descr "Resistor SMD 0402")
		(tags "resistor SMD 0402")
		(property "Reference" "R136"
			(at -1 1.63 90)
			(layer "B.SilkS")
			(effects
				(font
					(size 0.7 0.7)
					(thickness 0.15)
				)
				(justify right top mirror)
			)
		)
		(property "Value" "R_1k_0402"
			(at -1.011843 -1.772047 90)
			(layer "B.Fab")
			(effects
				(font
					(size 0.7 0.7)
					(thickness 0.15)
				)
				(justify right top mirror)
			)
		)
		(property "Datasheet" "https://www.bourns.com/docs/product-datasheets/cr.pdf"
			(at 0 0 90)
			(layer "B.Fab")
			(hide yes)
			(effects
				(font
					(size 1.27 1.27)
					(thickness 0.15)
				)
				(justify mirror)
			)
		)
		(property "Description" "SMD Chip Resistor, 1 kohm, ± 1%, 63 mW, 0402 [1005 Metric], Thick Film, General Purpose"
			(at 0 0 90)
			(layer "B.Fab")
			(hide yes)
			(effects
				(font
					(size 1.27 1.27)
					(thickness 0.15)
				)
				(justify mirror)
			)
		)
		(property "Manufacturer" "Bourns"
			(at 0 0 270)
			(unlocked yes)
			(layer "B.Fab")
			(hide yes)
			(effects
				(font
					(size 1 1)
					(thickness 0.15)
				)
				(justify mirror)
			)
		)
		(property "MPN" "CR0402-FX-1001GLF"
			(at 0 0 270)
			(unlocked yes)
			(layer "B.Fab")
			(hide yes)
			(effects
				(font
					(size 1 1)
					(thickness 0.15)
				)
				(justify mirror)
			)
		)
		(property "Val" "1k"
			(at 0 0 270)
			(unlocked yes)
			(layer "B.Fab")
			(hide yes)
			(effects
				(font
					(size 1 1)
					(thickness 0.15)
				)
				(justify mirror)
			)
		)
		(property "License" "Apache-2.0"
			(at 0 0 270)
			(unlocked yes)
			(layer "B.Fab")
			(hide yes)
			(effects
				(font
					(size 1 1)
					(thickness 0.15)
				)
				(justify mirror)
			)
		)
		(property "Author" "Antmicro"
			(at 0 0 270)
			(unlocked yes)
			(layer "B.Fab")
			(hide yes)
			(effects
				(font
					(size 1 1)
					(thickness 0.15)
				)
				(justify mirror)
			)
		)
		(property "Tolerance" "1%"
			(at 0 0 270)
			(unlocked yes)
			(layer "B.Fab")
			(hide yes)
			(effects
				(font
					(size 1 1)
					(thickness 0.15)
				)
				(justify mirror)
			)
		)
		(sheetname "/USB DP Alt mode/")
		(sheetfile "usb_dp.kicad_sch")
		(attr smd exclude_from_pos_files exclude_from_bom dnp)
		(fp_rect
			(start -0.925 0.47)
			(end 0.925 -0.47)
			(stroke
				(width 0.05)
				(type default)
			)
			(fill no)
			(layer "B.CrtYd")
		)
		(fp_rect
			(start -0.5 0.25)
			(end 0.5 -0.25)
			(stroke
				(width 0.15)
				(type solid)
			)
			(fill no)
			(layer "B.Fab")
		)
		(fp_text user "${REFERENCE}"
			(at -0.95 -3.168 90)
			(layer "B.Fab")
			(effects
				(font
					(size 0.7 0.7)
					(thickness 0.15)
				)
				(justify right top mirror)
			)
		)
		(fp_text user "License: Apache-2.0"
			(at -0.95 -5.169 90)
			(layer "B.Fab")
			(effects
				(font
					(size 0.7 0.7)
					(thickness 0.15)
				)
				(justify right top mirror)
			)
		)
		(fp_text user "Author: Antmicro"
			(at -0.95 -4.169 90)
			(layer "B.Fab")
			(effects
				(font
					(size 0.7 0.7)
					(thickness 0.15)
				)
				(justify right top mirror)
			)
		)
		(pad "1" smd roundrect
			(at -0.48 0 90)
			(size 0.59 0.64)
			(layers "B.Cu" "B.Mask" "B.Paste")
			(roundrect_rratio 0.25)
			(net 967 "/USB DP Alt mode/USBC1_DPEQ1")
			(pintype "passive")
		)
		(pad "2" smd roundrect
			(at 0.48 0 90)
			(size 0.59 0.64)
			(layers "B.Cu" "B.Mask" "B.Paste")
			(roundrect_rratio 0.25)
			(net 2 "+3V3")
			(pintype "passive")
		)
	)
	(footprint "antmicro-footprints:C_0402_1005Metric"
		(layer "B.Cu")
		(at 92.680003 105.5 -90)
		(descr "Capacitor SMD 0402")
		(tags "capacitor SMD 0402")
		(property "Reference" "C328"
			(at 0.9 -0.4 90)
			(layer "B.SilkS")
			(effects
				(font
					(size 0.7 0.7)
					(thickness 0.15)
				)
				(justify left bottom mirror)
			)
		)
		(property "Value" "C_100n_0402"
			(at -1.022927 -2.155213 90)
			(layer "B.Fab")
			(effects
				(font
					(size 0.7 0.7)
					(thickness 0.15)
				)
				(justify left bottom mirror)
			)
		)
		(property "Datasheet" "https://www.murata.com/products/productdetail?partno=GRM155R61H104KE14%23"
			(at 0 0 90)
			(layer "B.Fab")
			(hide yes)
			(effects
				(font
					(size 1.27 1.27)
					(thickness 0.15)
				)
				(justify mirror)
			)
		)
		(property "Description" "SMD Multilayer Ceramic Capacitor, 0.1 µF, 50 V, 0402 [1005 Metric], ± 10%, X5R, GRM Series"
			(at 0 0 90)
			(layer "B.Fab")
			(hide yes)
			(effects
				(font
					(size 1.27 1.27)
					(thickness 0.15)
				)
				(justify mirror)
			)
		)
		(property "Manufacturer" "Murata"
			(at 0 0 90)
			(unlocked yes)
			(layer "B.Fab")
			(hide yes)
			(effects
				(font
					(size 1 1)
					(thickness 0.15)
				)
				(justify mirror)
			)
		)
		(property "MPN" "GRM155R61H104KE14D"
			(at 0 0 90)
			(unlocked yes)
			(layer "B.Fab")
			(hide yes)
			(effects
				(font
					(size 1 1)
					(thickness 0.15)
				)
				(justify mirror)
			)
		)
		(property "Val" "100n"
			(at 0 0 90)
			(unlocked yes)
			(layer "B.Fab")
			(hide yes)
			(effects
				(font
					(size 1 1)
					(thickness 0.15)
				)
				(justify mirror)
			)
		)
		(property "License" "Apache-2.0"
			(at 0 0 90)
			(unlocked yes)
			(layer "B.Fab")
			(hide yes)
			(effects
				(font
					(size 1 1)
					(thickness 0.15)
				)
				(justify mirror)
			)
		)
		(property "Author" "Antmicro"
			(at 0 0 90)
			(unlocked yes)
			(layer "B.Fab")
			(hide yes)
			(effects
				(font
					(size 1 1)
					(thickness 0.15)
				)
				(justify mirror)
			)
		)
		(property "Voltage" "50V"
			(at 0 0 90)
			(unlocked yes)
			(layer "B.Fab")
			(hide yes)
			(effects
				(font
					(size 1 1)
					(thickness 0.15)
				)
				(justify mirror)
			)
		)
		(property "Dielectric" "X5R"
			(at 0 0 90)
			(unlocked yes)
			(layer "B.Fab")
			(hide yes)
			(effects
				(font
					(size 1 1)
					(thickness 0.15)
				)
				(justify mirror)
			)
		)
		(sheetname "/SoM_IO2/")
		(sheetfile "som_io2.kicad_sch")
		(attr smd)
		(fp_poly
			(pts
				(xy -0.925 0.47) (xy 0.925 0.47) (xy 0.925 -0.47) (xy -0.925 -0.47)
			)
			(stroke
				(width 0.05)
				(type default)
			)
			(fill no)
			(layer "B.CrtYd")
		)
		(fp_line
			(start -0.494 0.25)
			(end 0.504 0.25)
			(stroke
				(width 0.15)
				(type solid)
			)
			(layer "B.Fab")
		)
		(fp_line
			(start 0.504 0.25)
			(end 0.504 -0.248)
			(stroke
				(width 0.15)
				(type solid)
			)
			(layer "B.Fab")
		)
		(fp_line
			(start -0.494 -0.248)
			(end -0.494 0.25)
			(stroke
				(width 0.15)
				(type solid)
			)
			(layer "B.Fab")
		)
		(fp_line
			(start 0.504 -0.248)
			(end -0.494 -0.248)
			(stroke
				(width 0.15)
				(type solid)
			)
			(layer "B.Fab")
		)
		(fp_text user "License: Apache-2.0"
			(at -0.939 -5.799 90)
			(layer "B.Fab")
			(effects
				(font
					(size 0.7 0.7)
					(thickness 0.15)
				)
				(justify left bottom mirror)
			)
		)
		(fp_text user "${REFERENCE}"
			(at -0.939 -4.599 90)
			(layer "B.Fab")
			(effects
				(font
					(size 0.7 0.7)
					(thickness 0.15)
				)
				(justify left bottom mirror)
			)
		)
		(fp_text user "Author: Antmicro"
			(at -0.939 -3.399 90)
			(layer "B.Fab")
			(effects
				(font
					(size 0.7 0.7)
					(thickness 0.15)
				)
				(justify left bottom mirror)
			)
		)
		(pad "1" smd roundrect
			(at -0.48 0 270)
			(size 0.59 0.64)
			(layers "B.Cu" "B.Mask" "B.Paste")
			(roundrect_rratio 0.25)
			(net 603 "/Expansion connector/DP1.TX0-")
			(pintype "passive")
		)
		(pad "2" smd roundrect
			(at 0.48 0 270)
			(size 0.59 0.64)
			(layers "B.Cu" "B.Mask" "B.Paste")
			(roundrect_rratio 0.25)
			(net 1248 "/SoM_IO2/DP1.TX0_C-")
			(pintype "passive")
		)
	)
	(footprint "antmicro-footprints:R_0402_1005Metric"
		(layer "B.Cu")
		(at 200.8 125.2 180)
		(descr "Resistor SMD 0402")
		(tags "resistor SMD 0402")
		(property "Reference" "R324"
			(at -3.8 -0.398197 0)
			(layer "B.SilkS")
			(effects
				(font
					(size 0.7 0.7)
					(thickness 0.15)
				)
				(justify left bottom mirror)
			)
		)
		(property "Value" "R_200k_0402"
			(at -1.011843 -1.772046 0)
			(layer "B.Fab")
			(effects
				(font
					(size 0.7 0.7)
					(thickness 0.15)
				)
				(justify left bottom mirror)
			)
		)
		(property "Datasheet" "https://www.bourns.com/docs/product-datasheets/cr.pdf"
			(at 0 0 0)
			(layer "B.Fab")
			(hide yes)
			(effects
				(font
					(size 1.27 1.27)
					(thickness 0.15)
				)
				(justify mirror)
			)
		)
		(property "Description" "SMD Chip Resistor, 200 kohm, ± 1%, 62.5 mW, 0402 [1005 Metric], Thick Film, General Purpose"
			(at 0 0 0)
			(layer "B.Fab")
			(hide yes)
			(effects
				(font
					(size 1.27 1.27)
					(thickness 0.15)
				)
				(justify mirror)
			)
		)
		(property "MPN" "CR0402-FX-2003GLF"
			(at 0 0 0)
			(unlocked yes)
			(layer "B.Fab")
			(hide yes)
			(effects
				(font
					(size 1 1)
					(thickness 0.15)
				)
				(justify mirror)
			)
		)
		(property "Manufacturer" "Bourns"
			(at 0 0 0)
			(unlocked yes)
			(layer "B.Fab")
			(hide yes)
			(effects
				(font
					(size 1 1)
					(thickness 0.15)
				)
				(justify mirror)
			)
		)
		(property "License" "Apache-2.0"
			(at 0 0 0)
			(unlocked yes)
			(layer "B.Fab")
			(hide yes)
			(effects
				(font
					(size 1 1)
					(thickness 0.15)
				)
				(justify mirror)
			)
		)
		(property "Author" "Antmicro"
			(at 0 0 0)
			(unlocked yes)
			(layer "B.Fab")
			(hide yes)
			(effects
				(font
					(size 1 1)
					(thickness 0.15)
				)
				(justify mirror)
			)
		)
		(property "Val" "200k"
			(at 0 0 0)
			(unlocked yes)
			(layer "B.Fab")
			(hide yes)
			(effects
				(font
					(size 1 1)
					(thickness 0.15)
				)
				(justify mirror)
			)
		)
		(property "Tolerance" "1%"
			(at 0 0 0)
			(unlocked yes)
			(layer "B.Fab")
			(hide yes)
			(effects
				(font
					(size 1 1)
					(thickness 0.15)
				)
				(justify mirror)
			)
		)
		(sheetname "/USB Hub/")
		(sheetfile "usb_hub.kicad_sch")
		(attr smd)
		(fp_poly
			(pts
				(xy -0.925 0.47) (xy -0.925 -0.47) (xy 0.925 -0.47) (xy 0.925 0.47)
			)
			(stroke
				(width 0.05)
				(type default)
			)
			(fill no)
			(layer "B.CrtYd")
		)
		(fp_poly
			(pts
				(xy -0.5 0.25) (xy -0.5 -0.25) (xy 0.5 -0.25) (xy 0.5 0.25)
			)
			(stroke
				(width 0.15)
				(type solid)
			)
			(fill no)
			(layer "B.Fab")
		)
		(fp_text user "License: Apache-2.0"
			(at -0.949999 -5.169 0)
			(layer "B.Fab")
			(effects
				(font
					(size 0.7 0.7)
					(thickness 0.15)
				)
				(justify left bottom mirror)
			)
		)
		(fp_text user "Author: Antmicro"
			(at -0.95 -4.169 0)
			(layer "B.Fab")
			(effects
				(font
					(size 0.7 0.7)
					(thickness 0.15)
				)
				(justify left bottom mirror)
			)
		)
		(fp_text user "${REFERENCE}"
			(at -0.95 -3.168 0)
			(layer "B.Fab")
			(effects
				(font
					(size 0.7 0.7)
					(thickness 0.15)
				)
				(justify left bottom mirror)
			)
		)
		(pad "1" smd roundrect
			(at -0.48 0 180)
			(size 0.59 0.64)
			(layers "B.Cu" "B.Mask" "B.Paste")
			(roundrect_rratio 0.25)
			(net 1 "GND")
			(pintype "passive")
		)
		(pad "2" smd roundrect
			(at 0.48 0 180)
			(size 0.59 0.64)
			(layers "B.Cu" "B.Mask" "B.Paste")
			(roundrect_rratio 0.25)
			(net 925 "/USB Hub/HUB_SPI_D0")
			(pintype "passive")
		)
	)
)
